FILE_TYPE = CONNECTIVITY;
{Allegro Design Entry HDL 17.2-2016 S081 (4005846) 1/11/2022}
"PAGE_NUMBER" = 78;
0"NC";
END.
